# SCM (Grand Teton) — schematic netlist excerpt (pin names and nets, part order shuffled) for the footprints in the layout excerpt that follows; sources: Cadence DE-HDL packaged netlist, KiCad conversion of 12092022_DA0F0TMDCD0_F0T_Management_Board_D_brd_V3_OCP.brd

C55  Q_CAP  22UF 6.3V 20% X6S  pkg C0603  page 16 : A = P1V2_AUX ; B = GND
R672  Q_RES  0 5% CHIP  pkg 0402LF  page 29 : A = USB3_01_TXN_C ; B = USB3_FPNL_TXN

(kicad_pcb
	(version 20260206)
	(generator "pcbnew")
	(generator_version "10.0")
	(general
		(thickness 1.6)
		(legacy_teardrops no)
	)
	(paper "A4")
	(title_block
		(title "12092022_DA0F0TMDCD0_F0T_Management_Board_D_brd_V3_OCP.brd")
		(comment 1 "Grand Teton / footprints 1123-1124 of 1440")
	)
	(layers
		(0 "F.Cu" signal "TOP")
		(4 "In1.Cu" signal "GND")
		(6 "In2.Cu" signal "IN1")
		(8 "In3.Cu" signal "GND1")
		(10 "In4.Cu" signal "IN2")
		(12 "In5.Cu" signal "VCC")
		(14 "In6.Cu" signal "VCC1")
		(16 "In7.Cu" signal "IN3")
		(18 "In8.Cu" signal "GND2")
		(20 "In9.Cu" signal "IN4")
		(22 "In10.Cu" signal "GND3")
		(2 "B.Cu" signal "BOTTOM")
		(9 "F.Adhes" user "F.Adhesive")
		(11 "B.Adhes" user "B.Adhesive")
		(13 "F.Paste" user "Package Geometry/Pastemask Top")
		(15 "B.Paste" user "Package Geometry/Pastemask Bottom")
		(5 "F.SilkS" user "Ref Des/Silkscreen Top")
		(7 "B.SilkS" user "Ref Des/Silkscreen Bottom")
		(1 "F.Mask" user "Board Geometry/Soldermask Top")
		(3 "B.Mask" user "Board Geometry/Soldermask Bottom")
		(17 "Dwgs.User" user "User.Drawings")
		(19 "Cmts.User" user "User.Comments")
		(21 "Eco1.User" user "User.Eco1")
		(23 "Eco2.User" user "User.Eco2")
		(25 "Edge.Cuts" user "Board Geometry/Outline")
		(27 "Margin" user)
		(31 "F.CrtYd" user "Package Geometry/Place Bound Top")
		(29 "B.CrtYd" user "Package Geometry/Place Bound Bottom")
		(35 "F.Fab" user "Ref Des/Assembly Top")
		(33 "B.Fab" user "Ref Des/Assembly Bottom")
	)
	(footprint ""
		(layer "B.Cu")
		(at 45.339 -96.8248 -90)
		(property "Reference" "R672"
			(at 0 0 90)
			(layer "B.SilkS")
			(hide yes)
			(effects
				(font
					(size 1.27 1.27)
				)
				(justify mirror)
			)
		)
		(property "Value" ""
			(at 0 0 90)
			(layer "B.Fab")
			(effects
				(font
					(size 1.27 1.27)
				)
				(justify mirror)
			)
		)
		(duplicate_pad_numbers_are_jumpers no)
		(fp_line
			(start -0.7874 0.4064)
			(end 0.7874 0.4064)
			(stroke
				(width 0.1524)
				(type default)
			)
			(layer "B.SilkS")
		)
		(fp_line
			(start 0.7874 0.4064)
			(end 0.7874 -0.4064)
			(stroke
				(width 0.1524)
				(type default)
			)
			(layer "B.SilkS")
		)
		(fp_line
			(start -0.7874 -0.4064)
			(end -0.7874 0.4064)
			(stroke
				(width 0.1524)
				(type default)
			)
			(layer "B.SilkS")
		)
		(fp_line
			(start 0.7874 -0.4064)
			(end -0.7874 -0.4064)
			(stroke
				(width 0.1524)
				(type default)
			)
			(layer "B.SilkS")
		)
		(fp_line
			(start -0.67945 0.3048)
			(end -0.120396 0.3048)
			(stroke
				(width 0.1)
				(type default)
			)
			(layer "B.Fab")
		)
		(fp_line
			(start -0.120396 0.3048)
			(end -0.120396 0.2794)
			(stroke
				(width 0.1)
				(type default)
			)
			(layer "B.Fab")
		)
		(fp_line
			(start 0.12065 0.3048)
			(end 0.67945 0.3048)
			(stroke
				(width 0.1)
				(type default)
			)
			(layer "B.Fab")
		)
		(fp_line
			(start 0.67945 0.3048)
			(end 0.67945 -0.305054)
			(stroke
				(width 0.1)
				(type default)
			)
			(layer "B.Fab")
		)
		(fp_line
			(start -0.120396 0.2794)
			(end 0.12065 0.2794)
			(stroke
				(width 0.1)
				(type default)
			)
			(layer "B.Fab")
		)
		(fp_line
			(start 0.12065 0.2794)
			(end 0.12065 0.3048)
			(stroke
				(width 0.1)
				(type default)
			)
			(layer "B.Fab")
		)
		(fp_line
			(start -0.12065 -0.2794)
			(end -0.12065 -0.3048)
			(stroke
				(width 0.1)
				(type default)
			)
			(layer "B.Fab")
		)
		(fp_line
			(start 0.12065 -0.2794)
			(end -0.12065 -0.2794)
			(stroke
				(width 0.1)
				(type default)
			)
			(layer "B.Fab")
		)
		(fp_line
			(start -0.67945 -0.3048)
			(end -0.67945 0.3048)
			(stroke
				(width 0.1)
				(type default)
			)
			(layer "B.Fab")
		)
		(fp_line
			(start -0.12065 -0.3048)
			(end -0.67945 -0.3048)
			(stroke
				(width 0.1)
				(type default)
			)
			(layer "B.Fab")
		)
		(fp_line
			(start 0.12065 -0.305054)
			(end 0.12065 -0.2794)
			(stroke
				(width 0.1)
				(type default)
			)
			(layer "B.Fab")
		)
		(fp_line
			(start 0.67945 -0.305054)
			(end 0.12065 -0.305054)
			(stroke
				(width 0.1)
				(type default)
			)
			(layer "B.Fab")
		)
		(pad "1" smd circle
			(at 0.40005 0 90)
			(size 0 0)
			(layers "B.Cu" "B.Mask" "B.Paste")
			(net "USB3_01_TXN_C")
		)
		(pad "2" smd circle
			(at -0.40005 0 90)
			(size 0 0)
			(layers "B.Cu" "B.Mask" "B.Paste")
			(net "USB3_FPNL_TXN")
		)
	)
	(footprint ""
		(layer "B.Cu")
		(at 74.774552 -35.01898 180)
		(property "Reference" "C55"
			(at 0 0 0)
			(layer "B.SilkS")
			(hide yes)
			(effects
				(font
					(size 1.27 1.27)
				)
				(justify mirror)
			)
		)
		(property "Value" ""
			(at 0 0 0)
			(layer "B.Fab")
			(effects
				(font
					(size 1.27 1.27)
				)
				(justify mirror)
			)
		)
		(duplicate_pad_numbers_are_jumpers no)
		(fp_line
			(start 1.2954 0.5842)
			(end 1.2954 -0.5842)
			(stroke
				(width 0.1524)
				(type default)
			)
			(layer "B.SilkS")
		)
		(fp_line
			(start 1.2954 -0.5842)
			(end -1.2954 -0.5842)
			(stroke
				(width 0.1524)
				(type default)
			)
			(layer "B.SilkS")
		)
		(fp_line
			(start 0 -0.5842)
			(end 0 0.5842)
			(stroke
				(width 0.1524)
				(type default)
			)
			(layer "B.SilkS")
		)
		(fp_line
			(start -1.2954 0.5842)
			(end 1.2954 0.5842)
			(stroke
				(width 0.1524)
				(type default)
			)
			(layer "B.SilkS")
		)
		(fp_line
			(start -1.2954 -0.5842)
			(end -1.2954 0.5842)
			(stroke
				(width 0.1524)
				(type default)
			)
			(layer "B.SilkS")
		)
		(fp_line
			(start 1.1938 0.4064)
			(end 1.1938 -0.4064)
			(stroke
				(width 0.1)
				(type default)
			)
			(layer "B.Fab")
		)
		(fp_line
			(start 1.1938 -0.4064)
			(end 0.8636 -0.4064)
			(stroke
				(width 0.1)
				(type default)
			)
			(layer "B.Fab")
		)
		(fp_line
			(start 0.8636 0.4572)
			(end 0.8636 0.4064)
			(stroke
				(width 0.1)
				(type default)
			)
			(layer "B.Fab")
		)
		(fp_line
			(start 0.8636 0.4064)
			(end 1.1938 0.4064)
			(stroke
				(width 0.1)
				(type default)
			)
			(layer "B.Fab")
		)
		(fp_line
			(start 0.8636 -0.4064)
			(end 0.8636 -0.4572)
			(stroke
				(width 0.1)
				(type default)
			)
			(layer "B.Fab")
		)
		(fp_line
			(start 0.8636 -0.4572)
			(end -0.8636 -0.4572)
			(stroke
				(width 0.1)
				(type default)
			)
			(layer "B.Fab")
		)
		(fp_line
			(start -0.8636 0.4572)
			(end 0.8636 0.4572)
			(stroke
				(width 0.1)
				(type default)
			)
			(layer "B.Fab")
		)
		(fp_line
			(start -0.8636 0.4064)
			(end -0.8636 0.4572)
			(stroke
				(width 0.1)
				(type default)
			)
			(layer "B.Fab")
		)
		(fp_line
			(start -0.8636 -0.4064)
			(end -1.1938 -0.4064)
			(stroke
				(width 0.1)
				(type default)
			)
			(layer "B.Fab")
		)
		(fp_line
			(start -0.8636 -0.4572)
			(end -0.8636 -0.4064)
			(stroke
				(width 0.1)
				(type default)
			)
			(layer "B.Fab")
		)
		(fp_line
			(start -1.1938 0.4064)
			(end -0.8636 0.4064)
			(stroke
				(width 0.1)
				(type default)
			)
			(layer "B.Fab")
		)
		(fp_line
			(start -1.1938 -0.4064)
			(end -1.1938 0.4064)
			(stroke
				(width 0.1)
				(type default)
			)
			(layer "B.Fab")
		)
		(pad "1" smd rect
			(at 0.7366 0 90)
			(size 0.7112 0.8128)
			(layers "B.Cu" "B.Mask" "B.Paste")
			(net "P1V2_AUX")
		)
		(pad "2" smd rect
			(at -0.7366 0 90)
			(size 0.7112 0.8128)
			(layers "B.Cu" "B.Mask" "B.Paste")
			(net "GND")
		)
	)
)
